(kicad_pcb
	(version 20241229)
	(generator "pcbnew")
	(generator_version "9.0")
	(general
		(thickness 1.292)
		(legacy_teardrops no)
	)
	(paper "A4")
	(title_block
		(title "LPDDR5 Testbed")
		(date "2023-12-19")
		(rev "1.0.0")
		(comment 9 "footprints 89-95 of 160")
	)
	(layers
		(0 "F.Cu" signal)
		(4 "In1.Cu" power)
		(6 "In2.Cu" power)
		(8 "In3.Cu" signal)
		(10 "In4.Cu" signal)
		(2 "B.Cu" signal)
		(9 "F.Adhes" user "F.Adhesive")
		(11 "B.Adhes" user "B.Adhesive")
		(13 "F.Paste" user)
		(15 "B.Paste" user)
		(5 "F.SilkS" user "F.Silkscreen")
		(7 "B.SilkS" user "B.Silkscreen")
		(1 "F.Mask" user)
		(3 "B.Mask" user)
		(17 "Dwgs.User" user "User.Drawings")
		(19 "Cmts.User" user "User.Comments")
		(21 "Eco1.User" user "User.Eco1")
		(23 "Eco2.User" user "User.Eco2")
		(25 "Edge.Cuts" user)
		(27 "Margin" user)
		(31 "F.CrtYd" user "F.Courtyard")
		(29 "B.CrtYd" user "B.Courtyard")
		(35 "F.Fab" user)
		(33 "B.Fab" user)
	)
	(footprint "antmicro-footprints:R_0402_1005Metric"
		(layer "B.Cu")
		(at 163.95 90.9 90)
		(descr "Resistor SMD 0402")
		(tags "resistor SMD 0402")
		(property "Reference" "R64"
			(at -1.2 -0.65 90)
			(unlocked yes)
			(layer "B.SilkS")
			(effects
				(font
					(size 0.7 0.7)
					(thickness 0.15)
				)
				(justify right bottom mirror)
			)
		)
		(property "Value" "R_100R_0402"
			(at -1.011843 -1.772047 90)
			(layer "B.Fab")
			(effects
				(font
					(size 0.7 0.7)
					(thickness 0.15)
				)
				(justify right bottom mirror)
			)
		)
		(property "Author" "Antmicro"
			(at 254.85 -73.05 0)
			(layer "B.Fab")
			(hide yes)
			(effects
				(font
					(size 1 1)
					(thickness 0.15)
				)
				(justify mirror)
			)
		)
		(property "License" "Apache-2.0"
			(at 254.85 -73.05 0)
			(layer "B.Fab")
			(hide yes)
			(effects
				(font
					(size 1 1)
					(thickness 0.15)
				)
				(justify mirror)
			)
		)
		(property "MPN" "CR0402-FX-1000GLF"
			(at 254.85 -73.05 0)
			(layer "B.Fab")
			(hide yes)
			(effects
				(font
					(size 1 1)
					(thickness 0.15)
				)
				(justify mirror)
			)
		)
		(property "Manufacturer" "Bourns"
			(at 254.85 -73.05 0)
			(layer "B.Fab")
			(hide yes)
			(effects
				(font
					(size 1 1)
					(thickness 0.15)
				)
				(justify mirror)
			)
		)
		(property "Tolerance" "1%"
			(at 254.85 -73.05 0)
			(layer "B.Fab")
			(hide yes)
			(effects
				(font
					(size 1 1)
					(thickness 0.15)
				)
				(justify mirror)
			)
		)
		(property "Val" "100R"
			(at 254.85 -73.05 0)
			(layer "B.Fab")
			(hide yes)
			(effects
				(font
					(size 1 1)
					(thickness 0.15)
				)
				(justify mirror)
			)
		)
		(sheetname "Translators1")
		(sheetfile "translators.kicad_sch")
		(attr smd)
		(fp_rect
			(start -0.93 0.47)
			(end 0.93 -0.47)
			(stroke
				(width 0.05)
				(type solid)
			)
			(fill no)
			(layer "B.CrtYd")
		)
		(fp_rect
			(start -0.5 0.25)
			(end 0.5 -0.25)
			(stroke
				(width 0.15)
				(type solid)
			)
			(fill no)
			(layer "B.Fab")
		)
		(pad "1" smd roundrect
			(at -0.485 0 90)
			(size 0.59 0.64)
			(layers "B.Cu" "B.Mask" "B.Paste")
			(roundrect_rratio 0.25)
			(net 127 "/SODIMM/LPDDR5_IN_B.WCK0_N")
			(pintype "passive")
		)
		(pad "2" smd roundrect
			(at 0.485 0 90)
			(size 0.59 0.64)
			(layers "B.Cu" "B.Mask" "B.Paste")
			(roundrect_rratio 0.25)
			(net 109 "/LPDDR5/LPDDR5_B.WCK0_N")
			(pintype "passive")
		)
	)
	(footprint "antmicro-footprints:R_0402_1005Metric"
		(layer "B.Cu")
		(at 136.15 91.35 -90)
		(descr "Resistor SMD 0402")
		(tags "resistor SMD 0402")
		(property "Reference" "R54"
			(at -1.05 -1.45 90)
			(unlocked yes)
			(layer "B.SilkS")
			(effects
				(font
					(size 0.7 0.7)
					(thickness 0.15)
				)
				(justify left bottom mirror)
			)
		)
		(property "Value" "R_100R_0402"
			(at -1.011843 -1.772047 90)
			(layer "B.Fab")
			(effects
				(font
					(size 0.7 0.7)
					(thickness 0.15)
				)
				(justify left bottom mirror)
			)
		)
		(property "Author" "Antmicro"
			(at 44.8 227.5 0)
			(layer "B.Fab")
			(hide yes)
			(effects
				(font
					(size 1 1)
					(thickness 0.15)
				)
				(justify mirror)
			)
		)
		(property "License" "Apache-2.0"
			(at 44.8 227.5 0)
			(layer "B.Fab")
			(hide yes)
			(effects
				(font
					(size 1 1)
					(thickness 0.15)
				)
				(justify mirror)
			)
		)
		(property "MPN" "CR0402-FX-1000GLF"
			(at 44.8 227.5 0)
			(layer "B.Fab")
			(hide yes)
			(effects
				(font
					(size 1 1)
					(thickness 0.15)
				)
				(justify mirror)
			)
		)
		(property "Manufacturer" "Bourns"
			(at 44.8 227.5 0)
			(layer "B.Fab")
			(hide yes)
			(effects
				(font
					(size 1 1)
					(thickness 0.15)
				)
				(justify mirror)
			)
		)
		(property "Tolerance" "1%"
			(at 44.8 227.5 0)
			(layer "B.Fab")
			(hide yes)
			(effects
				(font
					(size 1 1)
					(thickness 0.15)
				)
				(justify mirror)
			)
		)
		(property "Val" "100R"
			(at 44.8 227.5 0)
			(layer "B.Fab")
			(hide yes)
			(effects
				(font
					(size 1 1)
					(thickness 0.15)
				)
				(justify mirror)
			)
		)
		(sheetname "Translators")
		(sheetfile "translators.kicad_sch")
		(attr smd)
		(fp_rect
			(start -0.93 0.47)
			(end 0.93 -0.47)
			(stroke
				(width 0.05)
				(type solid)
			)
			(fill no)
			(layer "B.CrtYd")
		)
		(fp_rect
			(start -0.5 0.25)
			(end 0.5 -0.25)
			(stroke
				(width 0.15)
				(type solid)
			)
			(fill no)
			(layer "B.Fab")
		)
		(pad "1" smd roundrect
			(at -0.485 0 270)
			(size 0.59 0.64)
			(layers "B.Cu" "B.Mask" "B.Paste")
			(roundrect_rratio 0.25)
			(net 50 "/LPDDR5/LPDDR5_A.CK_N")
			(pintype "passive")
		)
		(pad "2" smd roundrect
			(at 0.485 0 270)
			(size 0.59 0.64)
			(layers "B.Cu" "B.Mask" "B.Paste")
			(roundrect_rratio 0.25)
			(net 14 "GND")
			(pintype "passive")
		)
	)
	(footprint "antmicro-footprints:C_0402_1005Metric"
		(layer "B.Cu")
		(at 130.775 81.45)
		(descr "Capacitor SMD 0402")
		(tags "capacitor SMD 0402")
		(property "Reference" "C57"
			(at 0.825 0.35 0)
			(unlocked yes)
			(layer "B.SilkS")
			(effects
				(font
					(size 0.7 0.7)
					(thickness 0.15)
				)
				(justify right bottom mirror)
			)
		)
		(property "Value" "C_4u7_0402"
			(at -1.022927 -2.155213 0)
			(layer "B.Fab")
			(effects
				(font
					(size 0.7 0.7)
					(thickness 0.15)
				)
				(justify right bottom mirror)
			)
		)
		(property "Author" "Antmicro"
			(at 0 0 0)
			(layer "B.Fab")
			(hide yes)
			(effects
				(font
					(size 1 1)
					(thickness 0.15)
				)
				(justify mirror)
			)
		)
		(property "Dielectric" ""
			(at 0 0 0)
			(layer "B.Fab")
			(hide yes)
			(effects
				(font
					(size 1 1)
					(thickness 0.15)
				)
				(justify mirror)
			)
		)
		(property "License" "Apache-2.0"
			(at 0 0 0)
			(layer "B.Fab")
			(hide yes)
			(effects
				(font
					(size 1 1)
					(thickness 0.15)
				)
				(justify mirror)
			)
		)
		(property "MPN" "GRM155R61A475MEAAD"
			(at 0 0 0)
			(layer "B.Fab")
			(hide yes)
			(effects
				(font
					(size 1 1)
					(thickness 0.15)
				)
				(justify mirror)
			)
		)
		(property "Manufacturer" "Murata"
			(at 0 0 0)
			(layer "B.Fab")
			(hide yes)
			(effects
				(font
					(size 1 1)
					(thickness 0.15)
				)
				(justify mirror)
			)
		)
		(property "Val" "4u7"
			(at 0 0 0)
			(layer "B.Fab")
			(hide yes)
			(effects
				(font
					(size 1 1)
					(thickness 0.15)
				)
				(justify mirror)
			)
		)
		(property "Voltage" ""
			(at 0 0 0)
			(layer "B.Fab")
			(hide yes)
			(effects
				(font
					(size 1 1)
					(thickness 0.15)
				)
				(justify mirror)
			)
		)
		(sheetname "LPDDR5")
		(sheetfile "lpddr5.kicad_sch")
		(attr smd)
		(fp_rect
			(start -0.9659 0.481258)
			(end 0.9649 -0.458742)
			(stroke
				(width 0.05)
				(type solid)
			)
			(fill no)
			(layer "B.CrtYd")
		)
		(fp_line
			(start -0.499 -0.248)
			(end -0.499 0.25)
			(stroke
				(width 0.15)
				(type solid)
			)
			(layer "B.Fab")
		)
		(fp_line
			(start -0.499 0.25)
			(end 0.499 0.25)
			(stroke
				(width 0.15)
				(type solid)
			)
			(layer "B.Fab")
		)
		(fp_line
			(start 0.499 -0.248)
			(end -0.499 -0.248)
			(stroke
				(width 0.15)
				(type solid)
			)
			(layer "B.Fab")
		)
		(fp_line
			(start 0.499 0.25)
			(end 0.499 -0.248)
			(stroke
				(width 0.15)
				(type solid)
			)
			(layer "B.Fab")
		)
		(pad "1" smd roundrect
			(at -0.484 0)
			(size 0.59 0.64)
			(layers "B.Cu" "B.Mask" "B.Paste")
			(roundrect_rratio 0.25)
			(net 14 "GND")
			(pintype "passive")
		)
		(pad "2" smd roundrect
			(at 0.484 0)
			(size 0.59 0.64)
			(layers "B.Cu" "B.Mask" "B.Paste")
			(roundrect_rratio 0.25)
			(net 13 "+1V05")
			(pintype "passive")
		)
	)
	(footprint "antmicro-footprints:R_0402_1005Metric"
		(layer "B.Cu")
		(at 153.45 90.785 90)
		(descr "Resistor SMD 0402")
		(tags "resistor SMD 0402")
		(property "Reference" "R66"
			(at -1.215 -0.55 90)
			(unlocked yes)
			(layer "B.SilkS")
			(effects
				(font
					(size 0.7 0.7)
					(thickness 0.15)
				)
				(justify right bottom mirror)
			)
		)
		(property "Value" "R_100R_0402"
			(at -1.011843 -1.772047 90)
			(layer "B.Fab")
			(effects
				(font
					(size 0.7 0.7)
					(thickness 0.15)
				)
				(justify right bottom mirror)
			)
		)
		(property "Author" "Antmicro"
			(at 244.235 -62.665 0)
			(layer "B.Fab")
			(hide yes)
			(effects
				(font
					(size 1 1)
					(thickness 0.15)
				)
				(justify mirror)
			)
		)
		(property "License" "Apache-2.0"
			(at 244.235 -62.665 0)
			(layer "B.Fab")
			(hide yes)
			(effects
				(font
					(size 1 1)
					(thickness 0.15)
				)
				(justify mirror)
			)
		)
		(property "MPN" "CR0402-FX-1000GLF"
			(at 244.235 -62.665 0)
			(layer "B.Fab")
			(hide yes)
			(effects
				(font
					(size 1 1)
					(thickness 0.15)
				)
				(justify mirror)
			)
		)
		(property "Manufacturer" "Bourns"
			(at 244.235 -62.665 0)
			(layer "B.Fab")
			(hide yes)
			(effects
				(font
					(size 1 1)
					(thickness 0.15)
				)
				(justify mirror)
			)
		)
		(property "Tolerance" "1%"
			(at 244.235 -62.665 0)
			(layer "B.Fab")
			(hide yes)
			(effects
				(font
					(size 1 1)
					(thickness 0.15)
				)
				(justify mirror)
			)
		)
		(property "Val" "100R"
			(at 244.235 -62.665 0)
			(layer "B.Fab")
			(hide yes)
			(effects
				(font
					(size 1 1)
					(thickness 0.15)
				)
				(justify mirror)
			)
		)
		(sheetname "Translators1")
		(sheetfile "translators.kicad_sch")
		(attr smd)
		(fp_rect
			(start -0.93 0.47)
			(end 0.93 -0.47)
			(stroke
				(width 0.05)
				(type solid)
			)
			(fill no)
			(layer "B.CrtYd")
		)
		(fp_rect
			(start -0.5 0.25)
			(end 0.5 -0.25)
			(stroke
				(width 0.15)
				(type solid)
			)
			(fill no)
			(layer "B.Fab")
		)
		(pad "1" smd roundrect
			(at -0.485 0 90)
			(size 0.59 0.64)
			(layers "B.Cu" "B.Mask" "B.Paste")
			(roundrect_rratio 0.25)
			(net 138 "/SODIMM/LPDDR5_IN_B.WCK1_N")
			(pintype "passive")
		)
		(pad "2" smd roundrect
			(at 0.485 0 90)
			(size 0.59 0.64)
			(layers "B.Cu" "B.Mask" "B.Paste")
			(roundrect_rratio 0.25)
			(net 110 "/LPDDR5/LPDDR5_B.WCK1_N")
			(pintype "passive")
		)
	)
	(footprint "antmicro-footprints:R_0402_1005Metric"
		(layer "B.Cu")
		(at 106.25 79.7 90)
		(descr "Resistor SMD 0402")
		(tags "resistor SMD 0402")
		(property "Reference" "R26"
			(at -1.1 -0.75 90)
			(unlocked yes)
			(layer "B.SilkS")
			(effects
				(font
					(size 0.7 0.7)
					(thickness 0.15)
				)
				(justify right bottom mirror)
			)
		)
		(property "Value" "R_0R_0402"
			(at -1.011843 -1.772047 90)
			(layer "B.Fab")
			(effects
				(font
					(size 0.7 0.7)
					(thickness 0.15)
				)
				(justify right bottom mirror)
			)
		)
		(property "Author" "Antmicro"
			(at 185.95 -26.55 0)
			(layer "B.Fab")
			(hide yes)
			(effects
				(font
					(size 1 1)
					(thickness 0.15)
				)
				(justify mirror)
			)
		)
		(property "Current" "1A"
			(at 185.95 -26.55 0)
			(layer "B.Fab")
			(hide yes)
			(effects
				(font
					(size 1 1)
					(thickness 0.15)
				)
				(justify mirror)
			)
		)
		(property "License" "Apache-2.0"
			(at 185.95 -26.55 0)
			(layer "B.Fab")
			(hide yes)
			(effects
				(font
					(size 1 1)
					(thickness 0.15)
				)
				(justify mirror)
			)
		)
		(property "MPN" "ERJ2GE0R00X"
			(at 185.95 -26.55 0)
			(layer "B.Fab")
			(hide yes)
			(effects
				(font
					(size 1 1)
					(thickness 0.15)
				)
				(justify mirror)
			)
		)
		(property "Manufacturer" "Panasonic"
			(at 185.95 -26.55 0)
			(layer "B.Fab")
			(hide yes)
			(effects
				(font
					(size 1 1)
					(thickness 0.15)
				)
				(justify mirror)
			)
		)
		(property "Tolerance" ""
			(at 185.95 -26.55 0)
			(layer "B.Fab")
			(hide yes)
			(effects
				(font
					(size 1 1)
					(thickness 0.15)
				)
				(justify mirror)
			)
		)
		(property "Val" "0R"
			(at 185.95 -26.55 0)
			(layer "B.Fab")
			(hide yes)
			(effects
				(font
					(size 1 1)
					(thickness 0.15)
				)
				(justify mirror)
			)
		)
		(sheetname "SODIMM")
		(sheetfile "sodim.kicad_sch")
		(attr smd)
		(fp_rect
			(start -0.93 0.47)
			(end 0.93 -0.47)
			(stroke
				(width 0.05)
				(type solid)
			)
			(fill no)
			(layer "B.CrtYd")
		)
		(fp_rect
			(start -0.5 0.25)
			(end 0.5 -0.25)
			(stroke
				(width 0.15)
				(type solid)
			)
			(fill no)
			(layer "B.Fab")
		)
		(pad "1" smd roundrect
			(at -0.485 0 90)
			(size 0.59 0.64)
			(layers "B.Cu" "B.Mask" "B.Paste")
			(roundrect_rratio 0.25)
			(net 18 "/SODIMM/HSCL")
			(pintype "passive")
		)
		(pad "2" smd roundrect
			(at 0.485 0 90)
			(size 0.59 0.64)
			(layers "B.Cu" "B.Mask" "B.Paste")
			(roundrect_rratio 0.25)
			(net 39 "/Power supply/I2C.SCL")
			(pintype "passive")
		)
	)
	(footprint "antmicro-footprints:R_0402_1005Metric"
		(layer "B.Cu")
		(at 133.9 93.8425 90)
		(descr "Resistor SMD 0402")
		(tags "resistor SMD 0402")
		(property "Reference" "R99"
			(at -1.0575 -0.5 90)
			(unlocked yes)
			(layer "B.SilkS")
			(effects
				(font
					(size 0.7 0.7)
					(thickness 0.15)
				)
				(justify right bottom mirror)
			)
		)
		(property "Value" "R_100k_0402"
			(at -1.011843 -1.772047 90)
			(layer "B.Fab")
			(effects
				(font
					(size 0.7 0.7)
					(thickness 0.15)
				)
				(justify right bottom mirror)
			)
		)
		(property "Author" "Antmicro"
			(at 227.7425 -40.0575 0)
			(layer "B.Fab")
			(hide yes)
			(effects
				(font
					(size 1 1)
					(thickness 0.15)
				)
				(justify mirror)
			)
		)
		(property "License" "Apache-2.0"
			(at 227.7425 -40.0575 0)
			(layer "B.Fab")
			(hide yes)
			(effects
				(font
					(size 1 1)
					(thickness 0.15)
				)
				(justify mirror)
			)
		)
		(property "MPN" "CR0402-FX-1003GLF"
			(at 227.7425 -40.0575 0)
			(layer "B.Fab")
			(hide yes)
			(effects
				(font
					(size 1 1)
					(thickness 0.15)
				)
				(justify mirror)
			)
		)
		(property "Manufacturer" "Bourns"
			(at 227.7425 -40.0575 0)
			(layer "B.Fab")
			(hide yes)
			(effects
				(font
					(size 1 1)
					(thickness 0.15)
				)
				(justify mirror)
			)
		)
		(property "Tolerance" "1%"
			(at 227.7425 -40.0575 0)
			(layer "B.Fab")
			(hide yes)
			(effects
				(font
					(size 1 1)
					(thickness 0.15)
				)
				(justify mirror)
			)
		)
		(property "Val" "100k"
			(at 227.7425 -40.0575 0)
			(layer "B.Fab")
			(hide yes)
			(effects
				(font
					(size 1 1)
					(thickness 0.15)
				)
				(justify mirror)
			)
		)
		(sheetname "SODIMM")
		(sheetfile "sodim.kicad_sch")
		(attr smd exclude_from_pos_files exclude_from_bom dnp)
		(fp_rect
			(start -0.93 0.47)
			(end 0.93 -0.47)
			(stroke
				(width 0.05)
				(type solid)
			)
			(fill no)
			(layer "B.CrtYd")
		)
		(fp_rect
			(start -0.5 0.25)
			(end 0.5 -0.25)
			(stroke
				(width 0.15)
				(type solid)
			)
			(fill no)
			(layer "B.Fab")
		)
		(pad "1" smd roundrect
			(at -0.485 0 90)
			(size 0.59 0.64)
			(layers "B.Cu" "B.Mask" "B.Paste")
			(roundrect_rratio 0.25)
			(net 33 "Net-(J1-Pad130)")
			(pintype "passive")
		)
		(pad "2" smd roundrect
			(at 0.485 0 90)
			(size 0.59 0.64)
			(layers "B.Cu" "B.Mask" "B.Paste")
			(roundrect_rratio 0.25)
			(net 14 "GND")
			(pintype "passive")
		)
	)
	(footprint "antmicro-footprints:C_0402_1005Metric"
		(layer "B.Cu")
		(at 133.375 84.35 -90)
		(descr "Capacitor SMD 0402")
		(tags "capacitor SMD 0402")
		(property "Reference" "C51"
			(at 0.85 -0.425 90)
			(unlocked yes)
			(layer "B.SilkS")
			(effects
				(font
					(size 0.7 0.7)
					(thickness 0.15)
				)
				(justify left bottom mirror)
			)
		)
		(property "Value" "C_4u7_0402"
			(at -1.022927 -2.155213 90)
			(layer "B.Fab")
			(effects
				(font
					(size 0.7 0.7)
					(thickness 0.15)
				)
				(justify left bottom mirror)
			)
		)
		(property "Author" "Antmicro"
			(at 49.025 217.725 0)
			(layer "B.Fab")
			(hide yes)
			(effects
				(font
					(size 1 1)
					(thickness 0.15)
				)
				(justify mirror)
			)
		)
		(property "Dielectric" ""
			(at 49.025 217.725 0)
			(layer "B.Fab")
			(hide yes)
			(effects
				(font
					(size 1 1)
					(thickness 0.15)
				)
				(justify mirror)
			)
		)
		(property "License" "Apache-2.0"
			(at 49.025 217.725 0)
			(layer "B.Fab")
			(hide yes)
			(effects
				(font
					(size 1 1)
					(thickness 0.15)
				)
				(justify mirror)
			)
		)
		(property "MPN" "GRM155R61A475MEAAD"
			(at 49.025 217.725 0)
			(layer "B.Fab")
			(hide yes)
			(effects
				(font
					(size 1 1)
					(thickness 0.15)
				)
				(justify mirror)
			)
		)
		(property "Manufacturer" "Murata"
			(at 49.025 217.725 0)
			(layer "B.Fab")
			(hide yes)
			(effects
				(font
					(size 1 1)
					(thickness 0.15)
				)
				(justify mirror)
			)
		)
		(property "Val" "4u7"
			(at 49.025 217.725 0)
			(layer "B.Fab")
			(hide yes)
			(effects
				(font
					(size 1 1)
					(thickness 0.15)
				)
				(justify mirror)
			)
		)
		(property "Voltage" ""
			(at 49.025 217.725 0)
			(layer "B.Fab")
			(hide yes)
			(effects
				(font
					(size 1 1)
					(thickness 0.15)
				)
				(justify mirror)
			)
		)
		(sheetname "LPDDR5")
		(sheetfile "lpddr5.kicad_sch")
		(attr smd)
		(fp_rect
			(start -0.9659 0.481258)
			(end 0.9649 -0.458742)
			(stroke
				(width 0.05)
				(type solid)
			)
			(fill no)
			(layer "B.CrtYd")
		)
		(fp_line
			(start -0.499 0.25)
			(end 0.499 0.25)
			(stroke
				(width 0.15)
				(type solid)
			)
			(layer "B.Fab")
		)
		(fp_line
			(start 0.499 0.25)
			(end 0.499 -0.248)
			(stroke
				(width 0.15)
				(type solid)
			)
			(layer "B.Fab")
		)
		(fp_line
			(start -0.499 -0.248)
			(end -0.499 0.25)
			(stroke
				(width 0.15)
				(type solid)
			)
			(layer "B.Fab")
		)
		(fp_line
			(start 0.499 -0.248)
			(end -0.499 -0.248)
			(stroke
				(width 0.15)
				(type solid)
			)
			(layer "B.Fab")
		)
		(pad "1" smd roundrect
			(at -0.484 0 270)
			(size 0.59 0.64)
			(layers "B.Cu" "B.Mask" "B.Paste")
			(roundrect_rratio 0.25)
			(net 14 "GND")
			(pintype "passive")
		)
		(pad "2" smd roundrect
			(at 0.484 0 270)
			(size 0.59 0.64)
			(layers "B.Cu" "B.Mask" "B.Paste")
			(roundrect_rratio 0.25)
			(net 12 "+0V9")
			(pintype "passive")
		)
	)
)
